# S9S_MB_2U (Grand Teton) — schematic netlist excerpt (pin names and nets, part order shuffled) for the footprints in the layout excerpt that follows; sources: Cadence DE-HDL packaged netlist, KiCad conversion of 03242023_DA0F0TMBIJ0_F0T_Motherboard_J_brd_V01_OCP.brd

R3065  Q_RES  33.2 1% CHIP  pkg 0402LF  page 205 : A = FM_BIOS_POST_CMPLT_N ; B = FM_BIOS_POST_CMPLT_HDR_N
PJ46  Q_SHORT  EMPTY  pkg SM  page 274 : \1\ = VSENSE_PVCCFA_EHV_CPU0_DP ; \2\ = SH_PVCCFA_EHV_CPU0

PPQ1  MOSFET_NCH_1D3S  PSMNR58-30YLH EMPTY  pkg SOT1023  page 304
  \1\  = P12V_AUX
  \2\  = P12V_AUX
  \3\  = P12V_AUX
  \4\  = P12V_HSC_GATE_G5
  \5\  = P12V_MAIN_R

(kicad_pcb
	(version 20260206)
	(generator "pcbnew")
	(generator_version "10.0")
	(general
		(thickness 1.6)
		(legacy_teardrops no)
	)
	(paper "A4")
	(title_block
		(title "03242023_DA0F0TMBIJ0_F0T_Motherboard_J_brd_V01_OCP.brd")
		(comment 1 "Grand Teton / footprints 2404-2406 of 6105")
	)
	(layers
		(0 "F.Cu" signal "TOP")
		(4 "In1.Cu" signal "GND")
		(6 "In2.Cu" signal "IN1")
		(8 "In3.Cu" signal "GND1")
		(10 "In4.Cu" signal "IN2")
		(12 "In5.Cu" signal "GND2")
		(14 "In6.Cu" signal "IN3")
		(16 "In7.Cu" signal "GND3")
		(18 "In8.Cu" signal "VCC")
		(20 "In9.Cu" signal "VCC1")
		(22 "In10.Cu" signal "GND4")
		(24 "In11.Cu" signal "IN4")
		(26 "In12.Cu" signal "GND5")
		(28 "In13.Cu" signal "IN5")
		(30 "In14.Cu" signal "GND6")
		(32 "In15.Cu" signal "IN6")
		(34 "In16.Cu" signal "GND7")
		(2 "B.Cu" signal "BOTTOM")
		(9 "F.Adhes" user "F.Adhesive")
		(11 "B.Adhes" user "B.Adhesive")
		(13 "F.Paste" user "Package Geometry/Pastemask Top")
		(15 "B.Paste" user "Package Geometry/Pastemask Bottom")
		(5 "F.SilkS" user "Ref Des/Silkscreen Top")
		(7 "B.SilkS" user "Ref Des/Silkscreen Bottom")
		(1 "F.Mask" user "Board Geometry/Soldermask Top")
		(3 "B.Mask" user "Board Geometry/Soldermask Bottom")
		(17 "Dwgs.User" user "User.Drawings")
		(19 "Cmts.User" user "User.Comments")
		(21 "Eco1.User" user "User.Eco1")
		(23 "Eco2.User" user "User.Eco2")
		(25 "Edge.Cuts" user "Board Geometry/Outline")
		(27 "Margin" user)
		(31 "F.CrtYd" user "Package Geometry/Place Bound Top")
		(29 "B.CrtYd" user "Package Geometry/Place Bound Bottom")
		(35 "F.Fab" user "Ref Des/Assembly Top")
		(33 "B.Fab" user "Ref Des/Assembly Bottom")
	)
	(footprint ""
		(layer "F.Cu")
		(at 24.93137 -42.992802 180)
		(property "Reference" "R3065"
			(at 0 0 180)
			(layer "F.SilkS")
			(hide yes)
			(effects
				(font
					(size 1.27 1.27)
				)
			)
		)
		(property "Value" ""
			(at 0 0 180)
			(layer "F.Fab")
			(effects
				(font
					(size 1.27 1.27)
				)
			)
		)
		(duplicate_pad_numbers_are_jumpers no)
		(fp_line
			(start 0.7874 0.4064)
			(end -0.7874 0.4064)
			(stroke
				(width 0.1524)
				(type default)
			)
			(layer "F.SilkS")
		)
		(fp_line
			(start 0.7874 -0.4064)
			(end 0.7874 0.4064)
			(stroke
				(width 0.1524)
				(type default)
			)
			(layer "F.SilkS")
		)
		(fp_line
			(start -0.7874 0.4064)
			(end -0.7874 -0.4064)
			(stroke
				(width 0.1524)
				(type default)
			)
			(layer "F.SilkS")
		)
		(fp_line
			(start -0.7874 -0.4064)
			(end 0.7874 -0.4064)
			(stroke
				(width 0.1524)
				(type default)
			)
			(layer "F.SilkS")
		)
		(fp_line
			(start 0.67945 0.3048)
			(end 0.120396 0.3048)
			(stroke
				(width 0.1)
				(type default)
			)
			(layer "F.Fab")
		)
		(fp_line
			(start 0.67945 -0.3048)
			(end 0.67945 0.3048)
			(stroke
				(width 0.1)
				(type default)
			)
			(layer "F.Fab")
		)
		(fp_line
			(start 0.12065 -0.2794)
			(end 0.12065 -0.3048)
			(stroke
				(width 0.1)
				(type default)
			)
			(layer "F.Fab")
		)
		(fp_line
			(start 0.12065 -0.3048)
			(end 0.67945 -0.3048)
			(stroke
				(width 0.1)
				(type default)
			)
			(layer "F.Fab")
		)
		(fp_line
			(start 0.120396 0.3048)
			(end 0.120396 0.2794)
			(stroke
				(width 0.1)
				(type default)
			)
			(layer "F.Fab")
		)
		(fp_line
			(start 0.120396 0.2794)
			(end -0.12065 0.2794)
			(stroke
				(width 0.1)
				(type default)
			)
			(layer "F.Fab")
		)
		(fp_line
			(start -0.12065 0.3048)
			(end -0.67945 0.3048)
			(stroke
				(width 0.1)
				(type default)
			)
			(layer "F.Fab")
		)
		(fp_line
			(start -0.12065 0.2794)
			(end -0.12065 0.3048)
			(stroke
				(width 0.1)
				(type default)
			)
			(layer "F.Fab")
		)
		(fp_line
			(start -0.12065 -0.2794)
			(end 0.12065 -0.2794)
			(stroke
				(width 0.1)
				(type default)
			)
			(layer "F.Fab")
		)
		(fp_line
			(start -0.12065 -0.305054)
			(end -0.12065 -0.2794)
			(stroke
				(width 0.1)
				(type default)
			)
			(layer "F.Fab")
		)
		(fp_line
			(start -0.67945 0.3048)
			(end -0.67945 -0.305054)
			(stroke
				(width 0.1)
				(type default)
			)
			(layer "F.Fab")
		)
		(fp_line
			(start -0.67945 -0.305054)
			(end -0.12065 -0.305054)
			(stroke
				(width 0.1)
				(type default)
			)
			(layer "F.Fab")
		)
		(pad "1" smd circle
			(at -0.40005 0 180)
			(size 0 0)
			(layers "F.Cu" "F.Mask" "F.Paste")
			(net "FM_BIOS_POST_CMPLT_N")
		)
		(pad "2" smd circle
			(at 0.40005 0 180)
			(size 0 0)
			(layers "F.Cu" "F.Mask" "F.Paste")
			(net "FM_BIOS_POST_CMPLT_HDR_N")
		)
	)
	(footprint ""
		(layer "F.Cu")
		(at 242.291616 -398.78 90)
		(property "Reference" "PPQ1"
			(at -8.230108 -1.771396 0)
			(unlocked yes)
			(layer "F.SilkS")
			(effects
				(font
					(size 0.7874 0.5842)
					(thickness 0.1524)
				)
				(justify left)
			)
		)
		(property "Value" ""
			(at 0 0 90)
			(layer "F.Fab")
			(effects
				(font
					(size 1.27 1.27)
				)
			)
		)
		(duplicate_pad_numbers_are_jumpers no)
		(fp_line
			(start 2.350008 -2.649982)
			(end 2.350008 -2.4892)
			(stroke
				(width 0.1524)
				(type default)
			)
			(layer "F.SilkS")
		)
		(fp_line
			(start -2.350008 -2.649982)
			(end 2.350008 -2.649982)
			(stroke
				(width 0.1524)
				(type default)
			)
			(layer "F.SilkS")
		)
		(fp_line
			(start -2.350008 -2.4384)
			(end -2.350008 -2.649982)
			(stroke
				(width 0.1524)
				(type default)
			)
			(layer "F.SilkS")
		)
		(fp_line
			(start 2.350008 2.4892)
			(end 2.350008 2.649982)
			(stroke
				(width 0.1524)
				(type default)
			)
			(layer "F.SilkS")
		)
		(fp_line
			(start 2.350008 2.649982)
			(end -2.350008 2.649982)
			(stroke
				(width 0.1524)
				(type default)
			)
			(layer "F.SilkS")
		)
		(fp_line
			(start -2.350008 2.649982)
			(end -2.350008 2.413)
			(stroke
				(width 0.1524)
				(type default)
			)
			(layer "F.SilkS")
		)
		(fp_poly
			(pts
				(xy -3.717544 -1.905) (xy -4.758944 -2.3241) (xy -4.758944 -1.524)
			)
			(stroke
				(width 0)
				(type default)
			)
			(fill yes)
			(layer "F.SilkS")
		)
		(fp_line
			(start 2.350008 -2.649982)
			(end 2.350008 2.649982)
			(stroke
				(width 0.1)
				(type default)
			)
			(layer "F.Fab")
		)
		(fp_line
			(start -2.350008 -2.649982)
			(end 2.350008 -2.649982)
			(stroke
				(width 0.1)
				(type default)
			)
			(layer "F.Fab")
		)
		(fp_line
			(start 2.350008 2.649982)
			(end -2.350008 2.649982)
			(stroke
				(width 0.1)
				(type default)
			)
			(layer "F.Fab")
		)
		(fp_line
			(start -2.350008 2.649982)
			(end -2.350008 -2.649982)
			(stroke
				(width 0.1)
				(type default)
			)
			(layer "F.Fab")
		)
		(fp_poly
			(pts
				(xy -3.717544 -1.905) (xy -4.758944 -2.3241) (xy -4.758944 -1.524)
			)
			(stroke
				(width 0)
				(type default)
			)
			(fill yes)
			(layer "F.Fab")
		)
		(pad "1" smd rect
			(at -2.999994 -1.905)
			(size 0.7112 1.1684)
			(layers "F.Cu" "F.Mask" "F.Paste")
			(net "P12V_AUX")
		)
		(pad "2" smd rect
			(at -2.999994 -0.635)
			(size 0.7112 1.1684)
			(layers "F.Cu" "F.Mask" "F.Paste")
			(net "P12V_AUX")
		)
		(pad "3" smd rect
			(at -2.999994 0.635)
			(size 0.7112 1.1684)
			(layers "F.Cu" "F.Mask" "F.Paste")
			(net "P12V_AUX")
		)
		(pad "4" smd rect
			(at -2.999994 1.905)
			(size 0.7112 1.1684)
			(layers "F.Cu" "F.Mask" "F.Paste")
			(net "P12V_HSC_GATE_G5")
		)
		(pad "5" smd circle
			(at 0.925068 0)
			(size 0 0)
			(layers "F.Cu" "F.Mask" "F.Paste")
			(net "P12V_MAIN_R")
		)
		(zone
			(layer "F.Cu")
			(hatch none 0.5)
			(connect_pads
				(clearance 0)
			)
			(min_thickness 0.25)
			(keepout
				(tracks not_allowed)
				(vias allowed)
				(pads allowed)
				(copperpour not_allowed)
				(footprints allowed)
			)
			(placement
				(enabled no)
				(sheetname "")
			)
			(fill
				(thermal_gap 0.5)
				(thermal_bridge_width 0.5)
				(island_removal_mode 0)
			)
			(polygon
				(pts
					(xy 240.132616 -397.3322) (xy 244.450616 -397.3322) (xy 244.933216 -397.3322) (xy 244.933216 -396.4305)
					(xy 239.650016 -396.4305) (xy 239.650016 -397.3322)
				)
			)
		)
	)
	(footprint ""
		(layer "F.Cu")
		(at 421.780208 -141.756638 180)
		(property "Reference" "PJ46"
			(at 2.878328 1.442212 0)
			(unlocked yes)
			(layer "F.SilkS")
			(effects
				(font
					(size 0.7874 0.5842)
					(thickness 0.1524)
				)
				(justify left)
			)
		)
		(property "Value" ""
			(at 0 0 180)
			(layer "F.Fab")
			(effects
				(font
					(size 1.27 1.27)
				)
			)
		)
		(duplicate_pad_numbers_are_jumpers no)
		(pad "1" smd circle
			(at -0.7493 0 270)
			(size 0 0)
			(layers "F.Cu" "F.Mask" "F.Paste")
			(net "VSENSE_PVCCFA_EHV_CPU0_DP")
		)
		(pad "2" smd rect
			(at 0.7493 0 90)
			(size 0.7112 0.8128)
			(layers "F.Cu" "F.Mask" "F.Paste")
			(net "SH_PVCCFA_EHV_CPU0")
		)
		(zone
			(layer "F.Cu")
			(hatch none 0.5)
			(connect_pads
				(clearance 0)
			)
			(min_thickness 0.25)
			(keepout
				(tracks allowed)
				(vias not_allowed)
				(pads allowed)
				(copperpour not_allowed)
				(footprints allowed)
			)
			(placement
				(enabled no)
				(sheetname "")
			)
			(fill
				(thermal_gap 0.5)
				(thermal_bridge_width 0.5)
				(island_removal_mode 0)
			)
			(polygon
				(pts
					(xy 420.573708 -141.350238) (xy 422.961308 -141.350238) (xy 422.961308 -142.167864) (xy 420.573708 -142.167864)
				)
			)
		)
	)
)
